(kicad_pcb
	(version 20260206)
	(generator "pcbnew")
	(generator_version "10.0")
	(general
		(thickness 1.6)
		(legacy_teardrops no)
	)
	(paper "A4")
	(title_block
		(title "v1-chassis-manager — T6M_CM_d_v01_1031_1645.brd")
		(comment 1 "Open CloudServer (Microsoft) / footprints 1557-1566 of 2512")
	)
	(layers
		(0 "F.Cu" signal "TOP")
		(4 "In1.Cu" signal "GND1")
		(6 "In2.Cu" signal "IN1")
		(8 "In3.Cu" signal "VCC1")
		(10 "In4.Cu" signal "VCC2")
		(12 "In5.Cu" signal "GND2")
		(14 "In6.Cu" signal "IN2")
		(16 "In7.Cu" signal "IN3")
		(18 "In8.Cu" signal "GND3")
		(2 "B.Cu" signal "BOTTOM")
		(9 "F.Adhes" user "F.Adhesive")
		(11 "B.Adhes" user "B.Adhesive")
		(13 "F.Paste" user "Package Geometry/Pastemask Top")
		(15 "B.Paste" user "Package Geometry/Pastemask Bottom")
		(5 "F.SilkS" user "Ref Des/Silkscreen Top")
		(7 "B.SilkS" user "Ref Des/Silkscreen Bottom")
		(1 "F.Mask" user "Board Geometry/Soldermask Top")
		(3 "B.Mask" user "Board Geometry/Soldermask Bottom")
		(17 "Dwgs.User" user "User.Drawings")
		(19 "Cmts.User" user "User.Comments")
		(21 "Eco1.User" user "User.Eco1")
		(23 "Eco2.User" user "User.Eco2")
		(25 "Edge.Cuts" user "Board Geometry/Outline")
		(27 "Margin" user)
		(31 "F.CrtYd" user "Package Geometry/Place Bound Top")
		(29 "B.CrtYd" user "Package Geometry/Place Bound Bottom")
		(35 "F.Fab" user "Ref Des/Assembly Top")
		(33 "B.Fab" user "Ref Des/Assembly Bottom")
	)
	(footprint ""
		(layer "F.Cu")
		(at 69.755004 -166.748714 180)
		(property "Reference" "R662"
			(at 4.49072 0.046228 0)
			(unlocked yes)
			(layer "F.SilkS")
			(effects
				(font
					(size 0.7874 0.5842)
					(thickness 0.1524)
				)
				(justify left)
			)
		)
		(property "Value" ""
			(at 0 0 180)
			(layer "F.Fab")
			(effects
				(font
					(size 1.27 1.27)
				)
			)
		)
		(duplicate_pad_numbers_are_jumpers no)
		(fp_line
			(start 0.7874 0.4064)
			(end -0.7874 0.4064)
			(stroke
				(width 0.1524)
				(type default)
			)
			(layer "F.SilkS")
		)
		(fp_line
			(start 0.7874 -0.4064)
			(end 0.7874 0.4064)
			(stroke
				(width 0.1524)
				(type default)
			)
			(layer "F.SilkS")
		)
		(fp_line
			(start -0.7874 0.4064)
			(end -0.7874 -0.4064)
			(stroke
				(width 0.1524)
				(type default)
			)
			(layer "F.SilkS")
		)
		(fp_line
			(start -0.7874 -0.4064)
			(end 0.7874 -0.4064)
			(stroke
				(width 0.1524)
				(type default)
			)
			(layer "F.SilkS")
		)
		(fp_poly
			(pts
				(xy -0.508 0.2794) (xy -0.508 0.2286) (xy -0.635 0.2286) (xy -0.635 -0.254) (xy -0.5334 -0.254)
				(xy -0.5334 -0.2794) (xy 0.5334 -0.2794) (xy 0.5334 -0.254) (xy 0.635 -0.254) (xy 0.635 0.254) (xy 0.5334 0.254)
				(xy 0.5334 0.2794)
			)
			(stroke
				(width 0)
				(type default)
			)
			(fill no)
			(layer "F.CrtYd")
		)
		(pad "1" smd rect
			(at 0.40005 0 180)
			(size 0.4572 0.508)
			(layers "F.Cu" "F.Mask" "F.Paste")
			(net "CPLD123_RSV1")
		)
		(pad "2" smd rect
			(at -0.40005 0 180)
			(size 0.4572 0.508)
			(layers "F.Cu" "F.Mask" "F.Paste")
			(net "CPLD2_RSV1")
		)
	)
	(footprint ""
		(layer "B.Cu")
		(at 79.702406 -29.777436 -90)
		(property "Reference" "C157"
			(at 0.716534 1.106932 270)
			(unlocked yes)
			(layer "B.SilkS")
			(effects
				(font
					(size 0.7874 0.5842)
					(thickness 0.1524)
				)
				(justify left mirror)
			)
		)
		(property "Value" ""
			(at 0 0 90)
			(layer "B.Fab")
			(effects
				(font
					(size 1.27 1.27)
				)
				(justify mirror)
			)
		)
		(duplicate_pad_numbers_are_jumpers no)
		(fp_line
			(start -0.7874 0.4064)
			(end 0.7874 0.4064)
			(stroke
				(width 0.1524)
				(type default)
			)
			(layer "B.SilkS")
		)
		(fp_line
			(start 0.7874 0.4064)
			(end 0.7874 -0.4064)
			(stroke
				(width 0.1524)
				(type default)
			)
			(layer "B.SilkS")
		)
		(fp_line
			(start 0 0.381)
			(end 0 -0.381)
			(stroke
				(width 0.1524)
				(type default)
			)
			(layer "B.SilkS")
		)
		(fp_line
			(start -0.7874 -0.4064)
			(end -0.7874 0.4064)
			(stroke
				(width 0.1524)
				(type default)
			)
			(layer "B.SilkS")
		)
		(fp_line
			(start 0.7874 -0.4064)
			(end -0.7874 -0.4064)
			(stroke
				(width 0.1524)
				(type default)
			)
			(layer "B.SilkS")
		)
		(fp_poly
			(pts
				(xy 0.5334 0.254) (xy 0.635 0.254) (xy 0.635 0.2286) (xy 0.635 -0.254) (xy 0.5334 -0.254) (xy 0.5334 -0.2794)
				(xy -0.5334 -0.2794) (xy -0.5334 -0.254) (xy -0.635 -0.254) (xy -0.635 0.254) (xy -0.5334 0.254)
				(xy -0.5334 0.2794) (xy 0.508 0.2794) (xy 0.5334 0.2794)
			)
			(stroke
				(width 0)
				(type default)
			)
			(fill no)
			(layer "B.CrtYd")
		)
		(pad "1" smd rect
			(at -0.40005 0 90)
			(size 0.4572 0.508)
			(layers "B.Cu" "B.Mask" "B.Paste")
			(net "PV_VDDR_NODE1")
		)
		(pad "2" smd rect
			(at 0.40005 0 90)
			(size 0.4572 0.508)
			(layers "B.Cu" "B.Mask" "B.Paste")
			(net "GND")
		)
	)
	(footprint ""
		(layer "B.Cu")
		(at 65.048638 -73.928478 90)
		(property "Reference" "C106"
			(at -32.233362 -14.384528 270)
			(unlocked yes)
			(layer "B.SilkS")
			(effects
				(font
					(size 0.7874 0.5842)
					(thickness 0.1524)
				)
				(justify left mirror)
			)
		)
		(property "Value" ""
			(at 0 0 90)
			(layer "B.Fab")
			(effects
				(font
					(size 1.27 1.27)
				)
				(justify mirror)
			)
		)
		(duplicate_pad_numbers_are_jumpers no)
		(fp_line
			(start 0.7874 -0.4064)
			(end -0.7874 -0.4064)
			(stroke
				(width 0.1524)
				(type default)
			)
			(layer "B.SilkS")
		)
		(fp_line
			(start -0.7874 -0.4064)
			(end -0.7874 0.4064)
			(stroke
				(width 0.1524)
				(type default)
			)
			(layer "B.SilkS")
		)
		(fp_line
			(start 0 0.381)
			(end 0 -0.381)
			(stroke
				(width 0.1524)
				(type default)
			)
			(layer "B.SilkS")
		)
		(fp_line
			(start 0.7874 0.4064)
			(end 0.7874 -0.4064)
			(stroke
				(width 0.1524)
				(type default)
			)
			(layer "B.SilkS")
		)
		(fp_line
			(start -0.7874 0.4064)
			(end 0.7874 0.4064)
			(stroke
				(width 0.1524)
				(type default)
			)
			(layer "B.SilkS")
		)
		(fp_poly
			(pts
				(xy 0.5334 0.254) (xy 0.635 0.254) (xy 0.635 0.2286) (xy 0.635 -0.254) (xy 0.5334 -0.254) (xy 0.5334 -0.2794)
				(xy -0.5334 -0.2794) (xy -0.5334 -0.254) (xy -0.635 -0.254) (xy -0.635 0.254) (xy -0.5334 0.254)
				(xy -0.5334 0.2794) (xy 0.508 0.2794) (xy 0.5334 0.2794)
			)
			(stroke
				(width 0)
				(type default)
			)
			(fill no)
			(layer "B.CrtYd")
		)
		(pad "1" smd rect
			(at -0.40005 0 270)
			(size 0.4572 0.508)
			(layers "B.Cu" "B.Mask" "B.Paste")
			(net "P1V05_NODE1")
		)
		(pad "2" smd rect
			(at 0.40005 0 270)
			(size 0.4572 0.508)
			(layers "B.Cu" "B.Mask" "B.Paste")
			(net "GND")
		)
	)
	(footprint ""
		(layer "B.Cu")
		(at 88.77935 -71.145654)
		(property "Reference" "R174"
			(at -1.91516 9.466834 0)
			(unlocked yes)
			(layer "B.SilkS")
			(effects
				(font
					(size 0.7874 0.5842)
					(thickness 0.1524)
				)
				(justify left mirror)
			)
		)
		(property "Value" ""
			(at 0 0 0)
			(layer "B.Fab")
			(effects
				(font
					(size 1.27 1.27)
				)
				(justify mirror)
			)
		)
		(duplicate_pad_numbers_are_jumpers no)
		(fp_line
			(start -0.7874 -0.4064)
			(end -0.7874 0.4064)
			(stroke
				(width 0.1524)
				(type default)
			)
			(layer "B.SilkS")
		)
		(fp_line
			(start -0.7874 0.4064)
			(end 0.7874 0.4064)
			(stroke
				(width 0.1524)
				(type default)
			)
			(layer "B.SilkS")
		)
		(fp_line
			(start 0.7874 -0.4064)
			(end -0.7874 -0.4064)
			(stroke
				(width 0.1524)
				(type default)
			)
			(layer "B.SilkS")
		)
		(fp_line
			(start 0.7874 0.4064)
			(end 0.7874 -0.4064)
			(stroke
				(width 0.1524)
				(type default)
			)
			(layer "B.SilkS")
		)
		(fp_poly
			(pts
				(xy 0.508 0.2794) (xy 0.508 0.2286) (xy 0.635 0.2286) (xy 0.635 -0.254) (xy 0.5334 -0.254) (xy 0.5334 -0.2794)
				(xy -0.5334 -0.2794) (xy -0.5334 -0.254) (xy -0.635 -0.254) (xy -0.635 0.254) (xy -0.5334 0.254)
				(xy -0.5334 0.2794)
			)
			(stroke
				(width 0)
				(type default)
			)
			(fill no)
			(layer "B.CrtYd")
		)
		(pad "1" smd rect
			(at -0.40005 0 180)
			(size 0.4572 0.508)
			(layers "B.Cu" "B.Mask" "B.Paste")
			(net "GND")
		)
		(pad "2" smd rect
			(at 0.40005 0 180)
			(size 0.4572 0.508)
			(layers "B.Cu" "B.Mask" "B.Paste")
			(net "PD_CPU_NODE1_PUNIT_ST_ADDR1")
		)
	)
	(footprint ""
		(layer "B.Cu")
		(at 163.128452 -102.002082)
		(property "Reference" "C385"
			(at 4.541012 0.032766 0)
			(unlocked yes)
			(layer "B.SilkS")
			(effects
				(font
					(size 0.7874 0.5842)
					(thickness 0.1524)
				)
				(justify left mirror)
			)
		)
		(property "Value" ""
			(at 0 0 0)
			(layer "B.Fab")
			(effects
				(font
					(size 1.27 1.27)
				)
				(justify mirror)
			)
		)
		(duplicate_pad_numbers_are_jumpers no)
		(fp_line
			(start -0.7874 -0.4064)
			(end -0.7874 0.4064)
			(stroke
				(width 0.1524)
				(type default)
			)
			(layer "B.SilkS")
		)
		(fp_line
			(start -0.7874 0.4064)
			(end 0.7874 0.4064)
			(stroke
				(width 0.1524)
				(type default)
			)
			(layer "B.SilkS")
		)
		(fp_line
			(start 0 0.381)
			(end 0 -0.381)
			(stroke
				(width 0.1524)
				(type default)
			)
			(layer "B.SilkS")
		)
		(fp_line
			(start 0.7874 -0.4064)
			(end -0.7874 -0.4064)
			(stroke
				(width 0.1524)
				(type default)
			)
			(layer "B.SilkS")
		)
		(fp_line
			(start 0.7874 0.4064)
			(end 0.7874 -0.4064)
			(stroke
				(width 0.1524)
				(type default)
			)
			(layer "B.SilkS")
		)
		(fp_poly
			(pts
				(xy 0.5334 0.254) (xy 0.635 0.254) (xy 0.635 0.2286) (xy 0.635 -0.254) (xy 0.5334 -0.254) (xy 0.5334 -0.2794)
				(xy -0.5334 -0.2794) (xy -0.5334 -0.254) (xy -0.635 -0.254) (xy -0.635 0.254) (xy -0.5334 0.254)
				(xy -0.5334 0.2794) (xy 0.508 0.2794) (xy 0.5334 0.2794)
			)
			(stroke
				(width 0)
				(type default)
			)
			(fill no)
			(layer "B.CrtYd")
		)
		(pad "1" smd rect
			(at -0.40005 0 180)
			(size 0.4572 0.508)
			(layers "B.Cu" "B.Mask" "B.Paste")
			(net "P3V3_USB_NODE1")
		)
		(pad "2" smd rect
			(at 0.40005 0 180)
			(size 0.4572 0.508)
			(layers "B.Cu" "B.Mask" "B.Paste")
			(net "GND")
		)
	)
	(footprint ""
		(layer "B.Cu")
		(at 78.978506 -21.14296 90)
		(property "Reference" "C146"
			(at -5.852668 -0.770128 270)
			(unlocked yes)
			(layer "B.SilkS")
			(effects
				(font
					(size 0.7874 0.5842)
					(thickness 0.1524)
				)
				(justify left mirror)
			)
		)
		(property "Value" ""
			(at 0 0 90)
			(layer "B.Fab")
			(effects
				(font
					(size 1.27 1.27)
				)
				(justify mirror)
			)
		)
		(duplicate_pad_numbers_are_jumpers no)
		(fp_line
			(start 0.7874 -0.4064)
			(end -0.7874 -0.4064)
			(stroke
				(width 0.1524)
				(type default)
			)
			(layer "B.SilkS")
		)
		(fp_line
			(start -0.7874 -0.4064)
			(end -0.7874 0.4064)
			(stroke
				(width 0.1524)
				(type default)
			)
			(layer "B.SilkS")
		)
		(fp_line
			(start 0 0.381)
			(end 0 -0.381)
			(stroke
				(width 0.1524)
				(type default)
			)
			(layer "B.SilkS")
		)
		(fp_line
			(start 0.7874 0.4064)
			(end 0.7874 -0.4064)
			(stroke
				(width 0.1524)
				(type default)
			)
			(layer "B.SilkS")
		)
		(fp_line
			(start -0.7874 0.4064)
			(end 0.7874 0.4064)
			(stroke
				(width 0.1524)
				(type default)
			)
			(layer "B.SilkS")
		)
		(fp_poly
			(pts
				(xy 0.5334 0.254) (xy 0.635 0.254) (xy 0.635 0.2286) (xy 0.635 -0.254) (xy 0.5334 -0.254) (xy 0.5334 -0.2794)
				(xy -0.5334 -0.2794) (xy -0.5334 -0.254) (xy -0.635 -0.254) (xy -0.635 0.254) (xy -0.5334 0.254)
				(xy -0.5334 0.2794) (xy 0.508 0.2794) (xy 0.5334 0.2794)
			)
			(stroke
				(width 0)
				(type default)
			)
			(fill no)
			(layer "B.CrtYd")
		)
		(pad "1" smd rect
			(at -0.40005 0 270)
			(size 0.4572 0.508)
			(layers "B.Cu" "B.Mask" "B.Paste")
			(net "PV_VDDR_NODE1")
		)
		(pad "2" smd rect
			(at 0.40005 0 270)
			(size 0.4572 0.508)
			(layers "B.Cu" "B.Mask" "B.Paste")
			(net "GND")
		)
	)
	(footprint ""
		(layer "B.Cu")
		(at 176.1236 -192.582292 -90)
		(property "Reference" ""
			(at 0 0 90)
			(layer "B.SilkS")
			(hide yes)
			(effects
				(font
					(size 1.27 1.27)
				)
				(justify mirror)
			)
		)
		(property "Value" ""
			(at 0 0 90)
			(layer "B.Fab")
			(effects
				(font
					(size 1.27 1.27)
				)
				(justify mirror)
			)
		)
		(duplicate_pad_numbers_are_jumpers no)
		(fp_poly
			(pts
				(arc
					(start 0 -1.4986)
					(mid 0 1.4986)
					(end 0 -1.4986)
				)
			)
			(stroke
				(width 0)
				(type default)
			)
			(fill no)
			(layer "B.CrtYd")
		)
		(pad "1" smd circle
			(at 0 0 90)
			(size 0.9906 0.9906)
			(layers "B.Cu" "B.Mask" "B.Paste")
			(net "Net_38")
		)
		(zone
			(layer "B.Cu")
			(hatch none 0.5)
			(connect_pads
				(clearance 0)
			)
			(min_thickness 0.25)
			(keepout
				(tracks not_allowed)
				(vias allowed)
				(pads allowed)
				(copperpour not_allowed)
				(footprints allowed)
			)
			(placement
				(enabled no)
				(sheetname "")
			)
			(fill
				(thermal_gap 0.5)
				(thermal_bridge_width 0.5)
				(island_removal_mode 0)
			)
			(polygon
				(pts
					(arc
						(start 177.7492 -192.582292)
						(mid 174.498 -192.582292)
						(end 177.7492 -192.582292)
					)
				)
			)
		)
	)
	(footprint ""
		(layer "B.Cu")
		(at 69.96176 -185.205624 90)
		(property "Reference" "R923"
			(at 4.15163 -0.00635 270)
			(unlocked yes)
			(layer "B.SilkS")
			(effects
				(font
					(size 0.7874 0.5842)
					(thickness 0.1524)
				)
				(justify left mirror)
			)
		)
		(property "Value" ""
			(at 0 0 90)
			(layer "B.Fab")
			(effects
				(font
					(size 1.27 1.27)
				)
				(justify mirror)
			)
		)
		(duplicate_pad_numbers_are_jumpers no)
		(fp_line
			(start 0.7874 -0.4064)
			(end -0.7874 -0.4064)
			(stroke
				(width 0.1524)
				(type default)
			)
			(layer "B.SilkS")
		)
		(fp_line
			(start -0.7874 -0.4064)
			(end -0.7874 0.4064)
			(stroke
				(width 0.1524)
				(type default)
			)
			(layer "B.SilkS")
		)
		(fp_line
			(start 0.7874 0.4064)
			(end 0.7874 -0.4064)
			(stroke
				(width 0.1524)
				(type default)
			)
			(layer "B.SilkS")
		)
		(fp_line
			(start -0.7874 0.4064)
			(end 0.7874 0.4064)
			(stroke
				(width 0.1524)
				(type default)
			)
			(layer "B.SilkS")
		)
		(fp_poly
			(pts
				(xy 0.508 0.2794) (xy 0.508 0.2286) (xy 0.635 0.2286) (xy 0.635 -0.254) (xy 0.5334 -0.254) (xy 0.5334 -0.2794)
				(xy -0.5334 -0.2794) (xy -0.5334 -0.254) (xy -0.635 -0.254) (xy -0.635 0.254) (xy -0.5334 0.254)
				(xy -0.5334 0.2794)
			)
			(stroke
				(width 0)
				(type default)
			)
			(fill no)
			(layer "B.CrtYd")
		)
		(pad "1" smd rect
			(at -0.40005 0 270)
			(size 0.4572 0.508)
			(layers "B.Cu" "B.Mask" "B.Paste")
			(net "UART_T3_NODE3_TXD")
		)
		(pad "2" smd rect
			(at 0.40005 0 270)
			(size 0.4572 0.508)
			(layers "B.Cu" "B.Mask" "B.Paste")
			(net "UART_T3_NODE3_TXD_R")
		)
	)
	(footprint ""
		(layer "B.Cu")
		(at 68.246498 -96.696784 90)
		(property "Reference" "R110"
			(at -2.631694 -0.989584 270)
			(unlocked yes)
			(layer "B.SilkS")
			(effects
				(font
					(size 0.7874 0.5842)
					(thickness 0.1524)
				)
				(justify left mirror)
			)
		)
		(property "Value" ""
			(at 0 0 90)
			(layer "B.Fab")
			(effects
				(font
					(size 1.27 1.27)
				)
				(justify mirror)
			)
		)
		(duplicate_pad_numbers_are_jumpers no)
		(fp_line
			(start 0.7874 -0.4064)
			(end -0.7874 -0.4064)
			(stroke
				(width 0.1524)
				(type default)
			)
			(layer "B.SilkS")
		)
		(fp_line
			(start -0.7874 -0.4064)
			(end -0.7874 0.4064)
			(stroke
				(width 0.1524)
				(type default)
			)
			(layer "B.SilkS")
		)
		(fp_line
			(start 0.7874 0.4064)
			(end 0.7874 -0.4064)
			(stroke
				(width 0.1524)
				(type default)
			)
			(layer "B.SilkS")
		)
		(fp_line
			(start -0.7874 0.4064)
			(end 0.7874 0.4064)
			(stroke
				(width 0.1524)
				(type default)
			)
			(layer "B.SilkS")
		)
		(fp_poly
			(pts
				(xy 0.508 0.2794) (xy 0.508 0.2286) (xy 0.635 0.2286) (xy 0.635 -0.254) (xy 0.5334 -0.254) (xy 0.5334 -0.2794)
				(xy -0.5334 -0.2794) (xy -0.5334 -0.254) (xy -0.635 -0.254) (xy -0.635 0.254) (xy -0.5334 0.254)
				(xy -0.5334 0.2794)
			)
			(stroke
				(width 0)
				(type default)
			)
			(fill no)
			(layer "B.CrtYd")
		)
		(pad "1" smd rect
			(at -0.40005 0 270)
			(size 0.4572 0.508)
			(layers "B.Cu" "B.Mask" "B.Paste")
			(net "CPU_RSV_1_R")
		)
		(pad "2" smd rect
			(at 0.40005 0 270)
			(size 0.4572 0.508)
			(layers "B.Cu" "B.Mask" "B.Paste")
			(net "CPU_RSV_1")
		)
	)
	(footprint ""
		(layer "B.Cu")
		(at 155.661614 -64.971422 90)
		(property "Reference" "L30"
			(at -2.04343 6.068568 270)
			(unlocked yes)
			(layer "B.SilkS")
			(effects
				(font
					(size 0.7874 0.5842)
					(thickness 0.1524)
				)
				(justify left mirror)
			)
		)
		(property "Value" ""
			(at 0 0 90)
			(layer "B.Fab")
			(effects
				(font
					(size 1.27 1.27)
				)
				(justify mirror)
			)
		)
		(duplicate_pad_numbers_are_jumpers no)
		(fp_line
			(start 0.7874 -0.4064)
			(end -0.7874 -0.4064)
			(stroke
				(width 0.1524)
				(type default)
			)
			(layer "B.SilkS")
		)
		(fp_line
			(start -0.7874 -0.4064)
			(end -0.7874 0.4064)
			(stroke
				(width 0.1524)
				(type default)
			)
			(layer "B.SilkS")
		)
		(fp_line
			(start 0.7874 0.4064)
			(end 0.7874 -0.4064)
			(stroke
				(width 0.1524)
				(type default)
			)
			(layer "B.SilkS")
		)
		(fp_line
			(start 0.0889 0.4064)
			(end 0.0889 -0.4064)
			(stroke
				(width 0.1524)
				(type default)
			)
			(layer "B.SilkS")
		)
		(fp_line
			(start -0.0889 0.4064)
			(end -0.0889 -0.4064)
			(stroke
				(width 0.1524)
				(type default)
			)
			(layer "B.SilkS")
		)
		(fp_line
			(start -0.7874 0.4064)
			(end 0.7874 0.4064)
			(stroke
				(width 0.1524)
				(type default)
			)
			(layer "B.SilkS")
		)
		(fp_poly
			(pts
				(xy 0.5334 0.254) (xy 0.635 0.254) (xy 0.635 0.2286) (xy 0.635 -0.254) (xy 0.5334 -0.254) (xy 0.5334 -0.2794)
				(xy -0.5334 -0.2794) (xy -0.5334 -0.254) (xy -0.635 -0.254) (xy -0.635 0.254) (xy -0.5334 0.254)
				(xy -0.5334 0.2794) (xy 0.508 0.2794) (xy 0.5334 0.2794)
			)
			(stroke
				(width 0)
				(type default)
			)
			(fill no)
			(layer "B.CrtYd")
		)
		(pad "1" smd rect
			(at -0.40005 0 270)
			(size 0.4572 0.508)
			(layers "B.Cu" "B.Mask" "B.Paste")
			(net "P1V8_NODE1")
		)
		(pad "2" smd rect
			(at 0.40005 0 270)
			(size 0.4572 0.508)
			(layers "B.Cu" "B.Mask" "B.Paste")
			(net "P1V8_SATA_VAA2_0_NODE1")
		)
	)
)
